# T6G (Grand Teton) — schematic netlist excerpt (pin names and nets, part order shuffled) for the footprints in the layout excerpt that follows; sources: Cadence DE-HDL packaged netlist, KiCad conversion of 04192023_DAF0TMB3IC0_F0TG_MB_C_brd_V02_OCP.brd

R82  Q_RES  100K 1% CHIP  pkg 0402LF  page 132 : A = RMII_BMC_OCP_TX_EN ; B = GND
R1502  Q_RES  10K 5% CHIP  pkg 0402LF  page 76 : A = GND ; B = CLK_CPU1_RTCCLK

(kicad_pcb
	(version 20260206)
	(generator "pcbnew")
	(generator_version "10.0")
	(general
		(thickness 1.6)
		(legacy_teardrops no)
	)
	(paper "A4")
	(title_block
		(title "04192023_DAF0TMB3IC0_F0TG_MB_C_brd_V02_OCP.brd")
		(comment 1 "Grand Teton / footprints 7441-7442 of 8354")
	)
	(layers
		(0 "F.Cu" signal "TOP")
		(4 "In1.Cu" signal "GND")
		(6 "In2.Cu" signal "IN1")
		(8 "In3.Cu" signal "GND1")
		(10 "In4.Cu" signal "IN2")
		(12 "In5.Cu" signal "GND2")
		(14 "In6.Cu" signal "IN3")
		(16 "In7.Cu" signal "GND3")
		(18 "In8.Cu" signal "VCC")
		(20 "In9.Cu" signal "VCC1")
		(22 "In10.Cu" signal "GND4")
		(24 "In11.Cu" signal "IN4")
		(26 "In12.Cu" signal "GND5")
		(28 "In13.Cu" signal "IN5")
		(30 "In14.Cu" signal "GND6")
		(32 "In15.Cu" signal "IN6")
		(34 "In16.Cu" signal "GND7")
		(2 "B.Cu" signal "BOTTOM")
		(9 "F.Adhes" user "F.Adhesive")
		(11 "B.Adhes" user "B.Adhesive")
		(13 "F.Paste" user "Package Geometry/Pastemask Top")
		(15 "B.Paste" user "Package Geometry/Pastemask Bottom")
		(5 "F.SilkS" user "Ref Des/Silkscreen Top")
		(7 "B.SilkS" user "Ref Des/Silkscreen Bottom")
		(1 "F.Mask" user "Board Geometry/Soldermask Top")
		(3 "B.Mask" user "Board Geometry/Soldermask Bottom")
		(17 "Dwgs.User" user "User.Drawings")
		(19 "Cmts.User" user "User.Comments")
		(21 "Eco1.User" user "User.Eco1")
		(23 "Eco2.User" user "User.Eco2")
		(25 "Edge.Cuts" user "Board Geometry/Outline")
		(27 "Margin" user)
		(31 "F.CrtYd" user "Package Geometry/Place Bound Top")
		(29 "B.CrtYd" user "Package Geometry/Place Bound Bottom")
		(35 "F.Fab" user "Ref Des/Assembly Top")
		(33 "B.Fab" user "Ref Des/Assembly Bottom")
	)
	(footprint ""
		(layer "B.Cu")
		(at 146.010884 -320.525902 180)
		(property "Reference" "R1502"
			(at 0 0 0)
			(layer "B.SilkS")
			(hide yes)
			(effects
				(font
					(size 1.27 1.27)
				)
				(justify mirror)
			)
		)
		(property "Value" ""
			(at 0 0 0)
			(layer "B.Fab")
			(effects
				(font
					(size 1.27 1.27)
				)
				(justify mirror)
			)
		)
		(duplicate_pad_numbers_are_jumpers no)
		(fp_line
			(start 0.7874 0.4064)
			(end 0.7874 -0.4064)
			(stroke
				(width 0.1524)
				(type default)
			)
			(layer "B.SilkS")
		)
		(fp_line
			(start 0.7874 -0.4064)
			(end -0.7874 -0.4064)
			(stroke
				(width 0.1524)
				(type default)
			)
			(layer "B.SilkS")
		)
		(fp_line
			(start -0.7874 0.4064)
			(end 0.7874 0.4064)
			(stroke
				(width 0.1524)
				(type default)
			)
			(layer "B.SilkS")
		)
		(fp_line
			(start -0.7874 -0.4064)
			(end -0.7874 0.4064)
			(stroke
				(width 0.1524)
				(type default)
			)
			(layer "B.SilkS")
		)
		(fp_line
			(start 0.67945 0.3048)
			(end 0.67945 -0.305054)
			(stroke
				(width 0.1)
				(type default)
			)
			(layer "B.Fab")
		)
		(fp_line
			(start 0.67945 -0.305054)
			(end 0.12065 -0.305054)
			(stroke
				(width 0.1)
				(type default)
			)
			(layer "B.Fab")
		)
		(fp_line
			(start 0.12065 0.3048)
			(end 0.67945 0.3048)
			(stroke
				(width 0.1)
				(type default)
			)
			(layer "B.Fab")
		)
		(fp_line
			(start 0.12065 0.2794)
			(end 0.12065 0.3048)
			(stroke
				(width 0.1)
				(type default)
			)
			(layer "B.Fab")
		)
		(fp_line
			(start 0.12065 -0.2794)
			(end -0.12065 -0.2794)
			(stroke
				(width 0.1)
				(type default)
			)
			(layer "B.Fab")
		)
		(fp_line
			(start 0.12065 -0.305054)
			(end 0.12065 -0.2794)
			(stroke
				(width 0.1)
				(type default)
			)
			(layer "B.Fab")
		)
		(fp_line
			(start -0.120396 0.3048)
			(end -0.120396 0.2794)
			(stroke
				(width 0.1)
				(type default)
			)
			(layer "B.Fab")
		)
		(fp_line
			(start -0.120396 0.2794)
			(end 0.12065 0.2794)
			(stroke
				(width 0.1)
				(type default)
			)
			(layer "B.Fab")
		)
		(fp_line
			(start -0.12065 -0.2794)
			(end -0.12065 -0.3048)
			(stroke
				(width 0.1)
				(type default)
			)
			(layer "B.Fab")
		)
		(fp_line
			(start -0.12065 -0.3048)
			(end -0.67945 -0.3048)
			(stroke
				(width 0.1)
				(type default)
			)
			(layer "B.Fab")
		)
		(fp_line
			(start -0.67945 0.3048)
			(end -0.120396 0.3048)
			(stroke
				(width 0.1)
				(type default)
			)
			(layer "B.Fab")
		)
		(fp_line
			(start -0.67945 -0.3048)
			(end -0.67945 0.3048)
			(stroke
				(width 0.1)
				(type default)
			)
			(layer "B.Fab")
		)
		(pad "1" smd circle
			(at 0.40005 0)
			(size 0 0)
			(layers "B.Cu" "B.Mask" "B.Paste")
			(net "GND")
		)
		(pad "2" smd circle
			(at -0.40005 0)
			(size 0 0)
			(layers "B.Cu" "B.Mask" "B.Paste")
			(net "CLK_CPU1_RTCCLK")
		)
	)
	(footprint ""
		(layer "B.Cu")
		(at 191.192912 -70.459346)
		(property "Reference" "R82"
			(at 0 0 0)
			(layer "B.SilkS")
			(hide yes)
			(effects
				(font
					(size 1.27 1.27)
				)
				(justify mirror)
			)
		)
		(property "Value" ""
			(at 0 0 0)
			(layer "B.Fab")
			(effects
				(font
					(size 1.27 1.27)
				)
				(justify mirror)
			)
		)
		(duplicate_pad_numbers_are_jumpers no)
		(fp_line
			(start -0.7874 -0.4064)
			(end -0.7874 0.4064)
			(stroke
				(width 0.1524)
				(type default)
			)
			(layer "B.SilkS")
		)
		(fp_line
			(start -0.7874 0.4064)
			(end 0.7874 0.4064)
			(stroke
				(width 0.1524)
				(type default)
			)
			(layer "B.SilkS")
		)
		(fp_line
			(start 0.7874 -0.4064)
			(end -0.7874 -0.4064)
			(stroke
				(width 0.1524)
				(type default)
			)
			(layer "B.SilkS")
		)
		(fp_line
			(start 0.7874 0.4064)
			(end 0.7874 -0.4064)
			(stroke
				(width 0.1524)
				(type default)
			)
			(layer "B.SilkS")
		)
		(fp_line
			(start -0.67945 -0.3048)
			(end -0.67945 0.3048)
			(stroke
				(width 0.1)
				(type default)
			)
			(layer "B.Fab")
		)
		(fp_line
			(start -0.67945 0.3048)
			(end -0.120396 0.3048)
			(stroke
				(width 0.1)
				(type default)
			)
			(layer "B.Fab")
		)
		(fp_line
			(start -0.12065 -0.3048)
			(end -0.67945 -0.3048)
			(stroke
				(width 0.1)
				(type default)
			)
			(layer "B.Fab")
		)
		(fp_line
			(start -0.12065 -0.2794)
			(end -0.12065 -0.3048)
			(stroke
				(width 0.1)
				(type default)
			)
			(layer "B.Fab")
		)
		(fp_line
			(start -0.120396 0.2794)
			(end 0.12065 0.2794)
			(stroke
				(width 0.1)
				(type default)
			)
			(layer "B.Fab")
		)
		(fp_line
			(start -0.120396 0.3048)
			(end -0.120396 0.2794)
			(stroke
				(width 0.1)
				(type default)
			)
			(layer "B.Fab")
		)
		(fp_line
			(start 0.12065 -0.305054)
			(end 0.12065 -0.2794)
			(stroke
				(width 0.1)
				(type default)
			)
			(layer "B.Fab")
		)
		(fp_line
			(start 0.12065 -0.2794)
			(end -0.12065 -0.2794)
			(stroke
				(width 0.1)
				(type default)
			)
			(layer "B.Fab")
		)
		(fp_line
			(start 0.12065 0.2794)
			(end 0.12065 0.3048)
			(stroke
				(width 0.1)
				(type default)
			)
			(layer "B.Fab")
		)
		(fp_line
			(start 0.12065 0.3048)
			(end 0.67945 0.3048)
			(stroke
				(width 0.1)
				(type default)
			)
			(layer "B.Fab")
		)
		(fp_line
			(start 0.67945 -0.305054)
			(end 0.12065 -0.305054)
			(stroke
				(width 0.1)
				(type default)
			)
			(layer "B.Fab")
		)
		(fp_line
			(start 0.67945 0.3048)
			(end 0.67945 -0.305054)
			(stroke
				(width 0.1)
				(type default)
			)
			(layer "B.Fab")
		)
		(pad "1" smd circle
			(at 0.40005 0 180)
			(size 0 0)
			(layers "B.Cu" "B.Mask" "B.Paste")
			(net "RMII_BMC_OCP_TX_EN")
		)
		(pad "2" smd circle
			(at -0.40005 0 180)
			(size 0 0)
			(layers "B.Cu" "B.Mask" "B.Paste")
			(net "GND")
		)
	)
)
